# BASEBOARD_FAB2 (Tioga Pass) — schematic netlist excerpt (pin names and nets, part order shuffled) for the footprints in the layout excerpt that follows; sources: Cadence DE-HDL packaged netlist, KiCad conversion of Wiwynn_Tioga_Pass_MB.brd

R1D47  RES  10.0 1% CHIP  pkg 0402  page 200 : A = P12V_HSC_SENN0 ; B = A_HSC_HSN
R3P64  RES  1.00K 1% EMPTY  pkg 0402  page 126 : A = FM_FLASH_ATTACH_CFG_STRAP ; B = GND
R3D14  RES  2.2 1.0% CHIP  pkg 0603  page 102 : A = P3V3_DB1200 ; B = P3V3_DB1200_A

(kicad_pcb
	(version 20260206)
	(generator "pcbnew")
	(generator_version "10.0")
	(general
		(thickness 1.6)
		(legacy_teardrops no)
	)
	(paper "A4")
	(title_block
		(title "Wiwynn_Tioga_Pass_MB.brd")
		(comment 1 "Tioga Pass / footprints 1034-1036 of 4770")
	)
	(layers
		(0 "F.Cu" signal "TOP")
		(4 "In1.Cu" signal "L2GND")
		(6 "In2.Cu" signal "L3")
		(8 "In3.Cu" signal "L4GND")
		(10 "In4.Cu" signal "L5")
		(12 "In5.Cu" signal "L6GND")
		(14 "In6.Cu" signal "L7VCC")
		(16 "In7.Cu" signal "L8VCC")
		(18 "In8.Cu" signal "L9GND")
		(20 "In9.Cu" signal "L10")
		(22 "In10.Cu" signal "L11GND")
		(24 "In11.Cu" signal "L12")
		(26 "In12.Cu" signal "L13GND")
		(2 "B.Cu" signal "BOTTOM")
		(9 "F.Adhes" user "F.Adhesive")
		(11 "B.Adhes" user "B.Adhesive")
		(13 "F.Paste" user "Package Geometry/Pastemask Top")
		(15 "B.Paste" user "Package Geometry/Pastemask Bottom")
		(5 "F.SilkS" user "Ref Des/Silkscreen Top")
		(7 "B.SilkS" user "Ref Des/Silkscreen Bottom")
		(1 "F.Mask" user "Board Geometry/Soldermask Top")
		(3 "B.Mask" user "Board Geometry/Soldermask Bottom")
		(17 "Dwgs.User" user "User.Drawings")
		(19 "Cmts.User" user "User.Comments")
		(21 "Eco1.User" user "User.Eco1")
		(23 "Eco2.User" user "User.Eco2")
		(25 "Edge.Cuts" user "Board Geometry/Outline")
		(27 "Margin" user)
		(31 "F.CrtYd" user "Package Geometry/Place Bound Top")
		(29 "B.CrtYd" user "Package Geometry/Place Bound Bottom")
		(35 "F.Fab" user "Ref Des/Assembly Top")
		(33 "B.Fab" user "Ref Des/Assembly Bottom")
	)
	(footprint ""
		(layer "F.Cu")
		(at 10.414 -68.0593 180)
		(property "Reference" "R1D47"
			(at 0 0 180)
			(layer "F.SilkS")
			(hide yes)
			(effects
				(font
					(size 1.27 1.27)
				)
			)
		)
		(property "Value" ""
			(at 0 0 180)
			(layer "F.Fab")
			(effects
				(font
					(size 1.27 1.27)
				)
			)
		)
		(duplicate_pad_numbers_are_jumpers no)
		(fp_rect
			(start -0.2794 -0.1016)
			(end 0.2794 0.9906)
			(stroke
				(width 0)
				(type default)
			)
			(fill no)
			(layer "F.CrtYd")
		)
		(fp_line
			(start 0.2794 0.9906)
			(end 0.2794 -0.1016)
			(stroke
				(width 0.1)
				(type default)
			)
			(layer "F.Fab")
		)
		(fp_line
			(start 0.2794 -0.1016)
			(end -0.2794 -0.1016)
			(stroke
				(width 0.1)
				(type default)
			)
			(layer "F.Fab")
		)
		(fp_line
			(start -0.2794 0.9906)
			(end 0.2794 0.9906)
			(stroke
				(width 0.1)
				(type default)
			)
			(layer "F.Fab")
		)
		(fp_line
			(start -0.2794 -0.1016)
			(end -0.2794 0.9906)
			(stroke
				(width 0.1)
				(type default)
			)
			(layer "F.Fab")
		)
		(pad "1" smd rect
			(at 0 0 180)
			(size 0.508 0.508)
			(layers "F.Cu" "F.Mask" "F.Paste")
			(net "P12V_HSC_SENN0")
		)
		(pad "2" smd rect
			(at 0 0.889 180)
			(size 0.508 0.508)
			(layers "F.Cu" "F.Mask" "F.Paste")
			(net "A_HSC_HSN")
		)
		(zone
			(layer "F.Cu")
			(hatch none 0.5)
			(connect_pads
				(clearance 0)
			)
			(min_thickness 0.25)
			(keepout
				(tracks not_allowed)
				(vias allowed)
				(pads allowed)
				(copperpour not_allowed)
				(footprints allowed)
			)
			(placement
				(enabled no)
				(sheetname "")
			)
			(fill
				(thermal_gap 0.5)
				(thermal_bridge_width 0.5)
				(island_removal_mode 0)
			)
			(polygon
				(pts
					(xy 10.668 -68.3133) (xy 10.668 -68.6943) (xy 10.16 -68.6943) (xy 10.16 -68.3133)
				)
			)
		)
		(zone
			(layer "F.Cu")
			(hatch none 0.5)
			(connect_pads
				(clearance 0)
			)
			(min_thickness 0.25)
			(keepout
				(tracks allowed)
				(vias not_allowed)
				(pads allowed)
				(copperpour not_allowed)
				(footprints allowed)
			)
			(placement
				(enabled no)
				(sheetname "")
			)
			(fill
				(thermal_gap 0.5)
				(thermal_bridge_width 0.5)
				(island_removal_mode 0)
			)
			(polygon
				(pts
					(xy 10.668 -68.3133) (xy 10.668 -68.6943) (xy 10.16 -68.6943) (xy 10.16 -68.3133)
				)
			)
		)
	)
	(footprint ""
		(layer "F.Cu")
		(at 162.0012 -74.9808 90)
		(property "Reference" "R3D14"
			(at 0 0 90)
			(layer "F.SilkS")
			(hide yes)
			(effects
				(font
					(size 1.27 1.27)
				)
			)
		)
		(property "Value" ""
			(at 0 0 90)
			(layer "F.Fab")
			(effects
				(font
					(size 1.27 1.27)
				)
			)
		)
		(duplicate_pad_numbers_are_jumpers no)
		(fp_poly
			(pts
				(xy -0.4953 -0.2032) (xy 0.4953 -0.2032) (xy 0.4953 1.6002) (xy -0.4953 1.6002)
			)
			(stroke
				(width 0)
				(type default)
			)
			(fill no)
			(layer "F.CrtYd")
		)
		(fp_line
			(start 0.4953 -0.2032)
			(end 0.4953 1.6002)
			(stroke
				(width 0.1)
				(type default)
			)
			(layer "F.Fab")
		)
		(fp_line
			(start -0.4953 -0.2032)
			(end 0.4953 -0.2032)
			(stroke
				(width 0.1)
				(type default)
			)
			(layer "F.Fab")
		)
		(fp_line
			(start 0.4953 1.6002)
			(end -0.4953 1.6002)
			(stroke
				(width 0.1)
				(type default)
			)
			(layer "F.Fab")
		)
		(fp_line
			(start -0.4953 1.6002)
			(end -0.4953 -0.2032)
			(stroke
				(width 0.1)
				(type default)
			)
			(layer "F.Fab")
		)
		(pad "1" smd rect
			(at 0 0 90)
			(size 0.762 0.889)
			(layers "F.Cu" "F.Mask" "F.Paste")
			(net "P3V3_DB1200")
		)
		(pad "2" smd rect
			(at 0 1.397 90)
			(size 0.762 0.889)
			(layers "F.Cu" "F.Mask" "F.Paste")
			(net "P3V3_DB1200_A")
		)
		(zone
			(layer "F.Cu")
			(hatch none 0.5)
			(connect_pads
				(clearance 0)
			)
			(min_thickness 0.25)
			(keepout
				(tracks allowed)
				(vias not_allowed)
				(pads allowed)
				(copperpour not_allowed)
				(footprints allowed)
			)
			(placement
				(enabled no)
				(sheetname "")
			)
			(fill
				(thermal_gap 0.5)
				(thermal_bridge_width 0.5)
				(island_removal_mode 0)
			)
			(polygon
				(pts
					(xy 162.9537 -75.3618) (xy 162.4457 -75.3618) (xy 162.4457 -74.5998) (xy 162.9537 -74.5998)
				)
			)
		)
		(zone
			(layer "F.Cu")
			(hatch none 0.5)
			(connect_pads
				(clearance 0)
			)
			(min_thickness 0.25)
			(keepout
				(tracks not_allowed)
				(vias allowed)
				(pads allowed)
				(copperpour not_allowed)
				(footprints allowed)
			)
			(placement
				(enabled no)
				(sheetname "")
			)
			(fill
				(thermal_gap 0.5)
				(thermal_bridge_width 0.5)
				(island_removal_mode 0)
			)
			(polygon
				(pts
					(xy 162.9537 -74.5998) (xy 162.9537 -75.3618) (xy 162.4457 -75.3618) (xy 162.4457 -74.5998)
				)
			)
		)
	)
	(footprint ""
		(layer "F.Cu")
		(at 392.165078 -86.569042)
		(property "Reference" "R3P64"
			(at 0 0 0)
			(layer "F.SilkS")
			(hide yes)
			(effects
				(font
					(size 1.27 1.27)
				)
			)
		)
		(property "Value" ""
			(at 0 0 0)
			(layer "F.Fab")
			(effects
				(font
					(size 1.27 1.27)
				)
			)
		)
		(duplicate_pad_numbers_are_jumpers no)
		(fp_poly
			(pts
				(xy -0.2794 -0.1016) (xy 0.2794 -0.1016) (xy 0.2794 0.9906) (xy -0.2794 0.9906)
			)
			(stroke
				(width 0)
				(type default)
			)
			(fill no)
			(layer "F.CrtYd")
		)
		(fp_line
			(start -0.2794 -0.1016)
			(end -0.2794 0.9906)
			(stroke
				(width 0.1)
				(type default)
			)
			(layer "F.Fab")
		)
		(fp_line
			(start -0.2794 0.9906)
			(end 0.2794 0.9906)
			(stroke
				(width 0.1)
				(type default)
			)
			(layer "F.Fab")
		)
		(fp_line
			(start 0.2794 -0.1016)
			(end -0.2794 -0.1016)
			(stroke
				(width 0.1)
				(type default)
			)
			(layer "F.Fab")
		)
		(fp_line
			(start 0.2794 0.9906)
			(end 0.2794 -0.1016)
			(stroke
				(width 0.1)
				(type default)
			)
			(layer "F.Fab")
		)
		(pad "1" smd rect
			(at 0 0)
			(size 0.508 0.508)
			(layers "F.Cu" "F.Mask" "F.Paste")
			(net "FM_FLASH_ATTACH_CFG_STRAP")
		)
		(pad "2" smd rect
			(at 0 0.889)
			(size 0.508 0.508)
			(layers "F.Cu" "F.Mask" "F.Paste")
			(net "GND")
		)
		(zone
			(layer "F.Cu")
			(hatch none 0.5)
			(connect_pads
				(clearance 0)
			)
			(min_thickness 0.25)
			(keepout
				(tracks allowed)
				(vias not_allowed)
				(pads allowed)
				(copperpour not_allowed)
				(footprints allowed)
			)
			(placement
				(enabled no)
				(sheetname "")
			)
			(fill
				(thermal_gap 0.5)
				(thermal_bridge_width 0.5)
				(island_removal_mode 0)
			)
			(polygon
				(pts
					(xy 391.911078 -86.315042) (xy 392.419078 -86.315042) (xy 392.419078 -85.934042) (xy 391.911078 -85.934042)
				)
			)
		)
		(zone
			(layer "F.Cu")
			(hatch none 0.5)
			(connect_pads
				(clearance 0)
			)
			(min_thickness 0.25)
			(keepout
				(tracks not_allowed)
				(vias allowed)
				(pads allowed)
				(copperpour not_allowed)
				(footprints allowed)
			)
			(placement
				(enabled no)
				(sheetname "")
			)
			(fill
				(thermal_gap 0.5)
				(thermal_bridge_width 0.5)
				(island_removal_mode 0)
			)
			(polygon
				(pts
					(xy 391.911078 -85.934042) (xy 392.419078 -85.934042) (xy 392.419078 -86.315042) (xy 391.911078 -86.315042)
				)
			)
		)
	)
)
